# T6G (Grand Teton) — schematic netlist excerpt (pin names and nets, part order shuffled) for the footprints in the layout excerpt that follows; sources: Cadence DE-HDL packaged netlist, KiCad conversion of 04192023_DAF0TMB3IC0_F0TG_MB_C_brd_V02_OCP.brd

R4  Q_RES  4.7K 5% EMPTY  pkg 0402LF  page 238 : A = P3V3_AUX ; B = SMB_CPU_FRU_3V3AUX_SCL
R999  Q_RES  4.7K 5% CHIP  pkg 0402LF  page 145 : A = FM_LED_ACTIVE_E1S_0_R ; B = GND

(kicad_pcb
	(version 20260206)
	(generator "pcbnew")
	(generator_version "10.0")
	(general
		(thickness 1.6)
		(legacy_teardrops no)
	)
	(paper "A4")
	(title_block
		(title "04192023_DAF0TMB3IC0_F0TG_MB_C_brd_V02_OCP.brd")
		(comment 1 "Grand Teton / footprints 3411-3412 of 8354")
	)
	(layers
		(0 "F.Cu" signal "TOP")
		(4 "In1.Cu" signal "GND")
		(6 "In2.Cu" signal "IN1")
		(8 "In3.Cu" signal "GND1")
		(10 "In4.Cu" signal "IN2")
		(12 "In5.Cu" signal "GND2")
		(14 "In6.Cu" signal "IN3")
		(16 "In7.Cu" signal "GND3")
		(18 "In8.Cu" signal "VCC")
		(20 "In9.Cu" signal "VCC1")
		(22 "In10.Cu" signal "GND4")
		(24 "In11.Cu" signal "IN4")
		(26 "In12.Cu" signal "GND5")
		(28 "In13.Cu" signal "IN5")
		(30 "In14.Cu" signal "GND6")
		(32 "In15.Cu" signal "IN6")
		(34 "In16.Cu" signal "GND7")
		(2 "B.Cu" signal "BOTTOM")
		(9 "F.Adhes" user "F.Adhesive")
		(11 "B.Adhes" user "B.Adhesive")
		(13 "F.Paste" user "Package Geometry/Pastemask Top")
		(15 "B.Paste" user "Package Geometry/Pastemask Bottom")
		(5 "F.SilkS" user "Ref Des/Silkscreen Top")
		(7 "B.SilkS" user "Ref Des/Silkscreen Bottom")
		(1 "F.Mask" user "Board Geometry/Soldermask Top")
		(3 "B.Mask" user "Board Geometry/Soldermask Bottom")
		(17 "Dwgs.User" user "User.Drawings")
		(19 "Cmts.User" user "User.Comments")
		(21 "Eco1.User" user "User.Eco1")
		(23 "Eco2.User" user "User.Eco2")
		(25 "Edge.Cuts" user "Board Geometry/Outline")
		(27 "Margin" user)
		(31 "F.CrtYd" user "Package Geometry/Place Bound Top")
		(29 "B.CrtYd" user "Package Geometry/Place Bound Bottom")
		(35 "F.Fab" user "Ref Des/Assembly Top")
		(33 "B.Fab" user "Ref Des/Assembly Bottom")
	)
	(footprint ""
		(layer "F.Cu")
		(at 240.096802 -70.143624 90)
		(property "Reference" "R999"
			(at 0 0 90)
			(layer "F.SilkS")
			(hide yes)
			(effects
				(font
					(size 1.27 1.27)
				)
			)
		)
		(property "Value" ""
			(at 0 0 90)
			(layer "F.Fab")
			(effects
				(font
					(size 1.27 1.27)
				)
			)
		)
		(duplicate_pad_numbers_are_jumpers no)
		(fp_line
			(start 0.7874 -0.4064)
			(end 0.7874 0.4064)
			(stroke
				(width 0.1524)
				(type default)
			)
			(layer "F.SilkS")
		)
		(fp_line
			(start -0.7874 -0.4064)
			(end 0.7874 -0.4064)
			(stroke
				(width 0.1524)
				(type default)
			)
			(layer "F.SilkS")
		)
		(fp_line
			(start 0.7874 0.4064)
			(end -0.7874 0.4064)
			(stroke
				(width 0.1524)
				(type default)
			)
			(layer "F.SilkS")
		)
		(fp_line
			(start -0.7874 0.4064)
			(end -0.7874 -0.4064)
			(stroke
				(width 0.1524)
				(type default)
			)
			(layer "F.SilkS")
		)
		(fp_line
			(start -0.12065 -0.305054)
			(end -0.12065 -0.2794)
			(stroke
				(width 0.1)
				(type default)
			)
			(layer "F.Fab")
		)
		(fp_line
			(start -0.67945 -0.305054)
			(end -0.12065 -0.305054)
			(stroke
				(width 0.1)
				(type default)
			)
			(layer "F.Fab")
		)
		(fp_line
			(start 0.67945 -0.3048)
			(end 0.67945 0.3048)
			(stroke
				(width 0.1)
				(type default)
			)
			(layer "F.Fab")
		)
		(fp_line
			(start 0.12065 -0.3048)
			(end 0.67945 -0.3048)
			(stroke
				(width 0.1)
				(type default)
			)
			(layer "F.Fab")
		)
		(fp_line
			(start 0.12065 -0.2794)
			(end 0.12065 -0.3048)
			(stroke
				(width 0.1)
				(type default)
			)
			(layer "F.Fab")
		)
		(fp_line
			(start -0.12065 -0.2794)
			(end 0.12065 -0.2794)
			(stroke
				(width 0.1)
				(type default)
			)
			(layer "F.Fab")
		)
		(fp_line
			(start 0.120396 0.2794)
			(end -0.12065 0.2794)
			(stroke
				(width 0.1)
				(type default)
			)
			(layer "F.Fab")
		)
		(fp_line
			(start -0.12065 0.2794)
			(end -0.12065 0.3048)
			(stroke
				(width 0.1)
				(type default)
			)
			(layer "F.Fab")
		)
		(fp_line
			(start 0.67945 0.3048)
			(end 0.120396 0.3048)
			(stroke
				(width 0.1)
				(type default)
			)
			(layer "F.Fab")
		)
		(fp_line
			(start 0.120396 0.3048)
			(end 0.120396 0.2794)
			(stroke
				(width 0.1)
				(type default)
			)
			(layer "F.Fab")
		)
		(fp_line
			(start -0.12065 0.3048)
			(end -0.67945 0.3048)
			(stroke
				(width 0.1)
				(type default)
			)
			(layer "F.Fab")
		)
		(fp_line
			(start -0.67945 0.3048)
			(end -0.67945 -0.305054)
			(stroke
				(width 0.1)
				(type default)
			)
			(layer "F.Fab")
		)
		(pad "1" smd circle
			(at -0.40005 0 90)
			(size 0 0)
			(layers "F.Cu" "F.Mask" "F.Paste")
			(net "FM_LED_ACTIVE_E1S_0_R")
		)
		(pad "2" smd circle
			(at 0.40005 0 90)
			(size 0 0)
			(layers "F.Cu" "F.Mask" "F.Paste")
			(net "GND")
		)
	)
	(footprint ""
		(layer "F.Cu")
		(at 314.567316 -110.55477 180)
		(property "Reference" "R4"
			(at 0 0 180)
			(layer "F.SilkS")
			(hide yes)
			(effects
				(font
					(size 1.27 1.27)
				)
			)
		)
		(property "Value" ""
			(at 0 0 180)
			(layer "F.Fab")
			(effects
				(font
					(size 1.27 1.27)
				)
			)
		)
		(duplicate_pad_numbers_are_jumpers no)
		(fp_line
			(start 0.7874 0.4064)
			(end -0.7874 0.4064)
			(stroke
				(width 0.1524)
				(type default)
			)
			(layer "F.SilkS")
		)
		(fp_line
			(start 0.7874 -0.4064)
			(end 0.7874 0.4064)
			(stroke
				(width 0.1524)
				(type default)
			)
			(layer "F.SilkS")
		)
		(fp_line
			(start -0.7874 0.4064)
			(end -0.7874 -0.4064)
			(stroke
				(width 0.1524)
				(type default)
			)
			(layer "F.SilkS")
		)
		(fp_line
			(start -0.7874 -0.4064)
			(end 0.7874 -0.4064)
			(stroke
				(width 0.1524)
				(type default)
			)
			(layer "F.SilkS")
		)
		(fp_line
			(start 0.67945 0.3048)
			(end 0.120396 0.3048)
			(stroke
				(width 0.1)
				(type default)
			)
			(layer "F.Fab")
		)
		(fp_line
			(start 0.67945 -0.3048)
			(end 0.67945 0.3048)
			(stroke
				(width 0.1)
				(type default)
			)
			(layer "F.Fab")
		)
		(fp_line
			(start 0.12065 -0.2794)
			(end 0.12065 -0.3048)
			(stroke
				(width 0.1)
				(type default)
			)
			(layer "F.Fab")
		)
		(fp_line
			(start 0.12065 -0.3048)
			(end 0.67945 -0.3048)
			(stroke
				(width 0.1)
				(type default)
			)
			(layer "F.Fab")
		)
		(fp_line
			(start 0.120396 0.3048)
			(end 0.120396 0.2794)
			(stroke
				(width 0.1)
				(type default)
			)
			(layer "F.Fab")
		)
		(fp_line
			(start 0.120396 0.2794)
			(end -0.12065 0.2794)
			(stroke
				(width 0.1)
				(type default)
			)
			(layer "F.Fab")
		)
		(fp_line
			(start -0.12065 0.3048)
			(end -0.67945 0.3048)
			(stroke
				(width 0.1)
				(type default)
			)
			(layer "F.Fab")
		)
		(fp_line
			(start -0.12065 0.2794)
			(end -0.12065 0.3048)
			(stroke
				(width 0.1)
				(type default)
			)
			(layer "F.Fab")
		)
		(fp_line
			(start -0.12065 -0.2794)
			(end 0.12065 -0.2794)
			(stroke
				(width 0.1)
				(type default)
			)
			(layer "F.Fab")
		)
		(fp_line
			(start -0.12065 -0.305054)
			(end -0.12065 -0.2794)
			(stroke
				(width 0.1)
				(type default)
			)
			(layer "F.Fab")
		)
		(fp_line
			(start -0.67945 0.3048)
			(end -0.67945 -0.305054)
			(stroke
				(width 0.1)
				(type default)
			)
			(layer "F.Fab")
		)
		(fp_line
			(start -0.67945 -0.305054)
			(end -0.12065 -0.305054)
			(stroke
				(width 0.1)
				(type default)
			)
			(layer "F.Fab")
		)
		(pad "1" smd circle
			(at -0.40005 0 180)
			(size 0 0)
			(layers "F.Cu" "F.Mask" "F.Paste")
			(net "P3V3_AUX")
		)
		(pad "2" smd circle
			(at 0.40005 0 180)
			(size 0 0)
			(layers "F.Cu" "F.Mask" "F.Paste")
			(net "SMB_CPU_FRU_3V3AUX_SCL")
		)
	)
)
